# S9S_MB_2U (Grand Teton) — schematic netlist excerpt (pin names and nets, part order shuffled) for the footprints in the layout excerpt that follows; sources: Cadence DE-HDL packaged netlist, KiCad conversion of 03242023_DA0F0TMBIJ0_F0T_Motherboard_J_brd_V01_OCP.brd

PR1727  Q_RES  8.87K 1% EMPTY  pkg 0402LF  page 293 : A = PVCCINFAON_CPU1_LSET2 ; B = GND
PC526_P1_3  Q_CAP  2.2UF 10V 10% X6S  pkg C0402  page 286 : A = PVCCIN_CPU1_PVCC ; B = GND

(kicad_pcb
	(version 20260206)
	(generator "pcbnew")
	(generator_version "10.0")
	(general
		(thickness 1.6)
		(legacy_teardrops no)
	)
	(paper "A4")
	(title_block
		(title "03242023_DA0F0TMBIJ0_F0T_Motherboard_J_brd_V01_OCP.brd")
		(comment 1 "Grand Teton / footprints 1932-1933 of 6105")
	)
	(layers
		(0 "F.Cu" signal "TOP")
		(4 "In1.Cu" signal "GND")
		(6 "In2.Cu" signal "IN1")
		(8 "In3.Cu" signal "GND1")
		(10 "In4.Cu" signal "IN2")
		(12 "In5.Cu" signal "GND2")
		(14 "In6.Cu" signal "IN3")
		(16 "In7.Cu" signal "GND3")
		(18 "In8.Cu" signal "VCC")
		(20 "In9.Cu" signal "VCC1")
		(22 "In10.Cu" signal "GND4")
		(24 "In11.Cu" signal "IN4")
		(26 "In12.Cu" signal "GND5")
		(28 "In13.Cu" signal "IN5")
		(30 "In14.Cu" signal "GND6")
		(32 "In15.Cu" signal "IN6")
		(34 "In16.Cu" signal "GND7")
		(2 "B.Cu" signal "BOTTOM")
		(9 "F.Adhes" user "F.Adhesive")
		(11 "B.Adhes" user "B.Adhesive")
		(13 "F.Paste" user "Package Geometry/Pastemask Top")
		(15 "B.Paste" user "Package Geometry/Pastemask Bottom")
		(5 "F.SilkS" user "Ref Des/Silkscreen Top")
		(7 "B.SilkS" user "Ref Des/Silkscreen Bottom")
		(1 "F.Mask" user "Board Geometry/Soldermask Top")
		(3 "B.Mask" user "Board Geometry/Soldermask Bottom")
		(17 "Dwgs.User" user "User.Drawings")
		(19 "Cmts.User" user "User.Comments")
		(21 "Eco1.User" user "User.Eco1")
		(23 "Eco2.User" user "User.Eco2")
		(25 "Edge.Cuts" user "Board Geometry/Outline")
		(27 "Margin" user)
		(31 "F.CrtYd" user "Package Geometry/Place Bound Top")
		(29 "B.CrtYd" user "Package Geometry/Place Bound Bottom")
		(35 "F.Fab" user "Ref Des/Assembly Top")
		(33 "B.Fab" user "Ref Des/Assembly Bottom")
	)
	(footprint ""
		(layer "F.Cu")
		(at 109.744002 -333.525368 -90)
		(property "Reference" "PC526_P1_3"
			(at 0 0 270)
			(layer "F.SilkS")
			(hide yes)
			(effects
				(font
					(size 1.27 1.27)
				)
			)
		)
		(property "Value" ""
			(at 0 0 270)
			(layer "F.Fab")
			(effects
				(font
					(size 1.27 1.27)
				)
			)
		)
		(duplicate_pad_numbers_are_jumpers no)
		(fp_line
			(start -0.7874 0.4064)
			(end -0.7874 -0.4064)
			(stroke
				(width 0.1524)
				(type default)
			)
			(layer "F.SilkS")
		)
		(fp_line
			(start 0.7874 0.4064)
			(end -0.7874 0.4064)
			(stroke
				(width 0.1524)
				(type default)
			)
			(layer "F.SilkS")
		)
		(fp_line
			(start -0.7874 -0.4064)
			(end 0.7874 -0.4064)
			(stroke
				(width 0.1524)
				(type default)
			)
			(layer "F.SilkS")
		)
		(fp_line
			(start 0.7874 -0.4064)
			(end 0.7874 0.4064)
			(stroke
				(width 0.1524)
				(type default)
			)
			(layer "F.SilkS")
		)
		(fp_line
			(start -0.67945 0.3048)
			(end -0.67945 -0.305054)
			(stroke
				(width 0.1)
				(type default)
			)
			(layer "F.Fab")
		)
		(fp_line
			(start -0.12065 0.3048)
			(end -0.67945 0.3048)
			(stroke
				(width 0.1)
				(type default)
			)
			(layer "F.Fab")
		)
		(fp_line
			(start 0.120396 0.3048)
			(end 0.120396 0.2794)
			(stroke
				(width 0.1)
				(type default)
			)
			(layer "F.Fab")
		)
		(fp_line
			(start 0.67945 0.3048)
			(end 0.120396 0.3048)
			(stroke
				(width 0.1)
				(type default)
			)
			(layer "F.Fab")
		)
		(fp_line
			(start -0.12065 0.2794)
			(end -0.12065 0.3048)
			(stroke
				(width 0.1)
				(type default)
			)
			(layer "F.Fab")
		)
		(fp_line
			(start 0.120396 0.2794)
			(end -0.12065 0.2794)
			(stroke
				(width 0.1)
				(type default)
			)
			(layer "F.Fab")
		)
		(fp_line
			(start -0.12065 -0.2794)
			(end 0.12065 -0.2794)
			(stroke
				(width 0.1)
				(type default)
			)
			(layer "F.Fab")
		)
		(fp_line
			(start 0.12065 -0.2794)
			(end 0.12065 -0.3048)
			(stroke
				(width 0.1)
				(type default)
			)
			(layer "F.Fab")
		)
		(fp_line
			(start 0.12065 -0.3048)
			(end 0.67945 -0.3048)
			(stroke
				(width 0.1)
				(type default)
			)
			(layer "F.Fab")
		)
		(fp_line
			(start 0.67945 -0.3048)
			(end 0.67945 0.3048)
			(stroke
				(width 0.1)
				(type default)
			)
			(layer "F.Fab")
		)
		(fp_line
			(start -0.67945 -0.305054)
			(end -0.12065 -0.305054)
			(stroke
				(width 0.1)
				(type default)
			)
			(layer "F.Fab")
		)
		(fp_line
			(start -0.12065 -0.305054)
			(end -0.12065 -0.2794)
			(stroke
				(width 0.1)
				(type default)
			)
			(layer "F.Fab")
		)
		(pad "1" smd circle
			(at -0.40005 0 270)
			(size 0 0)
			(layers "F.Cu" "F.Mask" "F.Paste")
			(net "PVCCIN_CPU1_PVCC")
		)
		(pad "2" smd circle
			(at 0.40005 0 270)
			(size 0 0)
			(layers "F.Cu" "F.Mask" "F.Paste")
			(net "GND")
		)
	)
	(footprint ""
		(layer "F.Cu")
		(at 49.755552 -146.550634 90)
		(property "Reference" "PR1727"
			(at 0 0 90)
			(layer "F.SilkS")
			(hide yes)
			(effects
				(font
					(size 1.27 1.27)
				)
			)
		)
		(property "Value" ""
			(at 0 0 90)
			(layer "F.Fab")
			(effects
				(font
					(size 1.27 1.27)
				)
			)
		)
		(duplicate_pad_numbers_are_jumpers no)
		(fp_line
			(start 0.7874 -0.4064)
			(end 0.7874 0.4064)
			(stroke
				(width 0.1524)
				(type default)
			)
			(layer "F.SilkS")
		)
		(fp_line
			(start -0.7874 -0.4064)
			(end 0.7874 -0.4064)
			(stroke
				(width 0.1524)
				(type default)
			)
			(layer "F.SilkS")
		)
		(fp_line
			(start 0.7874 0.4064)
			(end -0.7874 0.4064)
			(stroke
				(width 0.1524)
				(type default)
			)
			(layer "F.SilkS")
		)
		(fp_line
			(start -0.7874 0.4064)
			(end -0.7874 -0.4064)
			(stroke
				(width 0.1524)
				(type default)
			)
			(layer "F.SilkS")
		)
		(fp_line
			(start -0.12065 -0.305054)
			(end -0.12065 -0.2794)
			(stroke
				(width 0.1)
				(type default)
			)
			(layer "F.Fab")
		)
		(fp_line
			(start -0.67945 -0.305054)
			(end -0.12065 -0.305054)
			(stroke
				(width 0.1)
				(type default)
			)
			(layer "F.Fab")
		)
		(fp_line
			(start 0.67945 -0.3048)
			(end 0.67945 0.3048)
			(stroke
				(width 0.1)
				(type default)
			)
			(layer "F.Fab")
		)
		(fp_line
			(start 0.12065 -0.3048)
			(end 0.67945 -0.3048)
			(stroke
				(width 0.1)
				(type default)
			)
			(layer "F.Fab")
		)
		(fp_line
			(start 0.12065 -0.2794)
			(end 0.12065 -0.3048)
			(stroke
				(width 0.1)
				(type default)
			)
			(layer "F.Fab")
		)
		(fp_line
			(start -0.12065 -0.2794)
			(end 0.12065 -0.2794)
			(stroke
				(width 0.1)
				(type default)
			)
			(layer "F.Fab")
		)
		(fp_line
			(start 0.120396 0.2794)
			(end -0.12065 0.2794)
			(stroke
				(width 0.1)
				(type default)
			)
			(layer "F.Fab")
		)
		(fp_line
			(start -0.12065 0.2794)
			(end -0.12065 0.3048)
			(stroke
				(width 0.1)
				(type default)
			)
			(layer "F.Fab")
		)
		(fp_line
			(start 0.67945 0.3048)
			(end 0.120396 0.3048)
			(stroke
				(width 0.1)
				(type default)
			)
			(layer "F.Fab")
		)
		(fp_line
			(start 0.120396 0.3048)
			(end 0.120396 0.2794)
			(stroke
				(width 0.1)
				(type default)
			)
			(layer "F.Fab")
		)
		(fp_line
			(start -0.12065 0.3048)
			(end -0.67945 0.3048)
			(stroke
				(width 0.1)
				(type default)
			)
			(layer "F.Fab")
		)
		(fp_line
			(start -0.67945 0.3048)
			(end -0.67945 -0.305054)
			(stroke
				(width 0.1)
				(type default)
			)
			(layer "F.Fab")
		)
		(pad "1" smd circle
			(at -0.40005 0 90)
			(size 0 0)
			(layers "F.Cu" "F.Mask" "F.Paste")
			(net "PVCCINFAON_CPU1_LSET2")
		)
		(pad "2" smd circle
			(at 0.40005 0 90)
			(size 0 0)
			(layers "F.Cu" "F.Mask" "F.Paste")
			(net "GND")
		)
	)
)
